FILE_TYPE = CONNECTIVITY;
{Allegro Design Entry HDL 17.2-2016 S081 (4005846) 1/11/2022}
"PAGE_NUMBER" = 94;
0"NC";
1"P3V3_AUX\g";
2"P12V_S3_AUX_CPU0_NVDIMM\g";
3"P12V_S3_AUX_CPU0_NVDIMM\g";
4"P3V3_AUX\g";
5"GND\g";
6"GND\g";
7"GND\g";
8"GND\g";
9"GND\g";
10"M_G_CPU0_SA_DQ<31:0>";
11"M_G_CPU0_SA_CB<7:0>";
12"M_G_CPU0_SB_CB<7:0>";
13"M_G_CPU0_SA_CA<6:0>";
14"M_G_CPU0_SB_CA<6:0>";
15"M_G_CPU0_SB_DQ<31:0>";
16"M_G_CPU0_SB_DQS_DP<9:0>";
17"M_G_CPU0_SA_DQS_DP<9:0>";
18"M_G_CPU0_SB_DQS_DN<9:0>";
19"M_G_CPU0_SA_DQS_DN<9:0>";
20"PD_CHG_CPU0_DIMM1_SAA";
21"I3C_SPD_DDREFGH_CPU0_LVC1_SDA";
22"I3C_SPD_DDREFGH_CPU0_LVC1_SCL_R5";
23"M_G_CPU0_ALERT_N";
24"RST_M_GH_CPU0_FPGA_N";
25"I3C_SPD_DDREFGH_CPU0_LVC1_SCL";
26"M_G_CPU0_SB_CB<0>";
27"M_G_CPU0_SA_CS_N<1>";
28"M_G_CPU0_SB_DQS_DP<2>";
29"M_G_CPU0_SB_DQS_DN<2>";
30"M_G_CPU0_SA_DQS_DN<7>";
31"M_G_CPU0_SA_DQS_DN<8>";
32"M_G_CPU0_SA_DQS_DN<9>";
33"M_G_CPU0_SA_DQS_DN<5>";
34"M_G_CPU0_SA_DQS_DN<6>";
35"M_G_CPU0_SA_DQS_DN<4>";
36"M_G_CPU0_SA_DQS_DN<3>";
37"M_G_CPU0_SA_DQS_DN<2>";
38"M_G_CPU0_SA_DQS_DN<1>";
39"M_G_CPU0_SA_DQS_DN<0>";
40"M_G_CPU0_SB_DQS_DN<8>";
41"M_G_CPU0_SB_DQS_DN<9>";
42"M_G_CPU0_SB_DQS_DN<6>";
43"M_G_CPU0_SB_DQS_DN<7>";
44"M_G_CPU0_SB_DQS_DN<5>";
45"M_G_CPU0_SB_DQS_DN<3>";
46"M_G_CPU0_SB_DQS_DN<4>";
47"M_G_CPU0_SB_DQS_DN<0>";
48"M_G_CPU0_SB_DQS_DN<1>";
49"M_G_CPU0_SA_DQS_DP<9>";
50"M_G_CPU0_SA_DQS_DP<7>";
51"M_G_CPU0_SA_DQS_DP<8>";
52"M_G_CPU0_SA_DQS_DP<4>";
53"M_G_CPU0_SA_DQS_DP<5>";
54"M_G_CPU0_SA_DQS_DP<6>";
55"M_G_CPU0_SA_DQS_DP<2>";
56"M_G_CPU0_SA_DQS_DP<3>";
57"M_G_CPU0_SA_DQS_DP<0>";
58"M_G_CPU0_SA_DQS_DP<1>";
59"M_G_CPU0_SB_DQS_DP<7>";
60"M_G_CPU0_SB_DQS_DP<8>";
61"M_G_CPU0_SB_DQS_DP<9>";
62"M_G_CPU0_SB_DQS_DP<6>";
63"M_G_CPU0_SB_DQS_DP<5>";
64"M_G_CPU0_SB_DQS_DP<4>";
65"M_G_CPU0_SB_DQS_DP<3>";
66"M_G_CPU0_SB_DQS_DP<0>";
67"M_G_CPU0_SB_DQS_DP<1>";
68"M_G_CPU0_SB_DQ<28>";
69"TP_CHG_CPU0_DIMM1_FRU_6";
70"TP_CHG_CPU0_DIMM1_FRU_0";
71"TP_CHG_CPU0_DIMM1_FRU_1";
72"TP_CHG_CPU0_DIMM1_FRU_2";
73"TP_CHG_CPU0_DIMM1_FRU_3";
74"TP_CHG_CPU0_DIMM1_FRU_4";
75"TP_CHG_CPU0_DIMM1_FRU_5";
76"PWRGD_CHG_CPU0_DIMM1";
77"M_G_CPU0_SB_PAR";
78"M_G_CPU0_SA_PAR";
79"M_G_CPU0_SB_RSP<0>";
80"M_G_CPU0_SA_RSP<0>";
81"M_G_CPU0_SB_DQ<0>";
82"M_G_CPU0_SB_DQ<1>";
83"M_G_CPU0_SB_DQ<2>";
84"M_G_CPU0_SB_DQ<3>";
85"M_G_CPU0_SB_DQ<4>";
86"M_G_CPU0_SB_DQ<5>";
87"M_G_CPU0_SB_DQ<6>";
88"M_G_CPU0_SB_DQ<7>";
89"M_G_CPU0_SB_DQ<8>";
90"M_G_CPU0_SB_DQ<9>";
91"M_G_CPU0_SB_DQ<10>";
92"M_G_CPU0_SB_DQ<11>";
93"M_G_CPU0_SB_DQ<12>";
94"M_G_CPU0_SB_DQ<13>";
95"M_G_CPU0_SB_DQ<14>";
96"M_G_CPU0_SB_DQ<15>";
97"M_G_CPU0_SB_DQ<16>";
98"M_G_CPU0_SB_DQ<17>";
99"M_G_CPU0_SB_DQ<18>";
100"M_G_CPU0_SB_DQ<19>";
101"M_G_CPU0_SB_DQ<20>";
102"M_G_CPU0_SB_DQ<21>";
103"M_G_CPU0_SB_DQ<22>";
104"M_G_CPU0_SB_DQ<23>";
105"M_G_CPU0_SB_DQ<24>";
106"M_G_CPU0_SB_DQ<25>";
107"M_G_CPU0_SB_DQ<26>";
108"M_G_CPU0_SB_DQ<27>";
109"M_G_CPU0_SB_DQ<29>";
110"M_G_CPU0_SB_DQ<30>";
111"M_G_CPU0_SB_DQ<31>";
112"M_G_CPU0_SA_DQ<0>";
113"M_G_CPU0_SA_DQ<1>";
114"M_G_CPU0_SA_DQ<2>";
115"M_G_CPU0_SA_DQ<3>";
116"M_G_CPU0_SA_DQ<4>";
117"M_G_CPU0_SA_DQ<5>";
118"M_G_CPU0_SA_DQ<6>";
119"M_G_CPU0_SA_DQ<7>";
120"M_G_CPU0_SA_DQ<8>";
121"M_G_CPU0_SA_DQ<9>";
122"M_G_CPU0_SA_DQ<10>";
123"M_G_CPU0_SA_DQ<11>";
124"M_G_CPU0_SA_DQ<12>";
125"M_G_CPU0_SA_DQ<13>";
126"M_G_CPU0_SA_DQ<14>";
127"M_G_CPU0_SA_DQ<15>";
128"M_G_CPU0_SA_DQ<16>";
129"M_G_CPU0_SA_DQ<17>";
130"M_G_CPU0_SA_DQ<18>";
131"M_G_CPU0_SA_DQ<19>";
132"M_G_CPU0_SA_DQ<20>";
133"M_G_CPU0_SA_DQ<21>";
134"M_G_CPU0_SA_DQ<22>";
135"M_G_CPU0_SA_DQ<23>";
136"M_G_CPU0_SA_DQ<24>";
137"M_G_CPU0_SA_DQ<25>";
138"M_G_CPU0_SA_DQ<26>";
139"M_G_CPU0_SA_DQ<27>";
140"M_G_CPU0_SA_DQ<28>";
141"M_G_CPU0_SA_DQ<29>";
142"M_G_CPU0_SA_DQ<30>";
143"M_G_CPU0_SB_CS_N<1>";
144"M_G_CPU0_SB_CS_N<0>";
145"M_G_CPU0_SA_CS_N<0>";
146"M_G_CPU0_CLK_DP<0>";
147"M_G_CPU0_CLK_DN<0>";
148"M_G_CPU0_SB_CB<1>";
149"M_G_CPU0_SB_CB<2>";
150"M_G_CPU0_SB_CB<3>";
151"M_G_CPU0_SB_CB<4>";
152"M_G_CPU0_SB_CB<5>";
153"M_G_CPU0_SB_CB<6>";
154"M_G_CPU0_SA_CB<0>";
155"M_G_CPU0_SA_CB<2>";
156"M_G_CPU0_SA_CB<3>";
157"M_G_CPU0_SA_CB<5>";
158"M_G_CPU0_SA_CB<6>";
159"M_G_CPU0_SB_CA<6>";
160"M_G_CPU0_SA_CA<6>";
161"M_G_CPU0_SB_CA<5>";
162"M_G_CPU0_SA_CA<5>";
163"M_G_CPU0_SB_CA<4>";
164"M_G_CPU0_SA_CA<4>";
165"M_G_CPU0_SB_CA<3>";
166"M_G_CPU0_SA_CA<3>";
167"M_G_CPU0_SB_CA<2>";
168"M_G_CPU0_SA_CA<2>";
169"M_G_CPU0_SB_CA<1>";
170"M_G_CPU0_SA_CA<1>";
171"M_G_CPU0_SB_CA<0>";
172"M_G_CPU0_SA_CA<0>";
173"M_G_CPU0_SB_CB<7>";
174"M_G_CPU0_SA_CB<1>";
175"M_G_CPU0_SA_CB<4>";
176"M_G_CPU0_SA_CB<7>";
177"M_G_CPU0_SA_DQ<31>";
178"PD_CHG_CPU0_DIMM1_SAA";
%"Q_RES"
"2","(-1950,200)","0","pure_quanta","I10";
;
PART_NUMBER"CS35492FB03"
VALUE"54.9K"
TOLERANCE"1%"
MATERIAL"CHIP"
WATTAGE"1/16W"
PACK_TYPE"0402LF"
$LOCATION"R38"
CDS_LIB"pure_quanta"
CDS_LOCATION"R38"
$SEC"1"
CDS_SEC"1";
"A"
$PN"1"178;
"B"
$PN"2"5;
%"TAP"
"1","(-525,3800)","0","standard","I100";
;
CDS_LIB"standard"
BODY_TYPE"PLUMBING"
HDL_TAP"TRUE";
"B \NAC \NWC"10;
"S \NAC"
BN"20"132;
%"TAP"
"1","(-525,3850)","0","standard","I101";
;
CDS_LIB"standard"
BODY_TYPE"PLUMBING"
HDL_TAP"TRUE";
"B \NAC \NWC"10;
"S \NAC"
BN"21"133;
%"TAP"
"1","(-525,3900)","0","standard","I102";
;
CDS_LIB"standard"
BODY_TYPE"PLUMBING"
HDL_TAP"TRUE";
"B \NAC \NWC"10;
"S \NAC"
BN"22"134;
%"TAP"
"1","(-525,4000)","0","standard","I103";
;
CDS_LIB"standard"
BODY_TYPE"PLUMBING"
HDL_TAP"TRUE";
"B \NAC \NWC"10;
"S \NAC"
BN"24"136;
%"TAP"
"1","(-525,3950)","0","standard","I104";
;
CDS_LIB"standard"
BODY_TYPE"PLUMBING"
HDL_TAP"TRUE";
"B \NAC \NWC"10;
"S \NAC"
BN"23"135;
%"TAP"
"1","(-2175,4100)","2","standard","I107";
;
CDS_LIB"standard"
BODY_TYPE"PLUMBING"
HDL_TAP"TRUE";
"B \NAC \NWC"13;
"S \NAC"
BN"1"170;
%"TAP"
"1","(-2175,4050)","2","standard","I108";
;
CDS_LIB"standard"
BODY_TYPE"PLUMBING"
HDL_TAP"TRUE";
"B \NAC \NWC"13;
"S \NAC"
BN"0"172;
%"TAP"
"1","(-2175,4150)","2","standard","I109";
;
CDS_LIB"standard"
BODY_TYPE"PLUMBING"
HDL_TAP"TRUE";
"B \NAC \NWC"13;
"S \NAC"
BN"2"168;
%"SCONN288_ADR50017P130CC"
"1","(-1350,2625)","0","pure_quanta","I11";
;
PART_NUMBER"DFHST8FS461"
MATERIAL"IO"
PART_TYPE"SMLF"
VALUE"SCONN288_ADR50017-P130CC"
$LOCATION"J13"
NEEDS_NO_SIZE"TRUE"
CDS_LMAN_SYM_OUTLINE"-450,1875,450,-1875"
CDS_LIB"pure_quanta"
CDS_LOCATION"J13"
$SEC"1"
CDS_SEC"1";
"DQ31_A"
$PN"194"177;
"CB7_A"
$PN"205"176;
"CB4_A"
$PN"58"175;
"CB1_A"
$PN"53"174;
"CB7_B"
$PN"236"173;
"ALERT_N \B"
$PN"62"23;
"CA0_A"
$PN"66"172;
"CA0_B"
$PN"76"171;
"CA1_A"
$PN"211"170;
"CA1_B"
$PN"221"169;
"CA2_A"
$PN"68"168;
"CA2_B"
$PN"78"167;
"CA3_A"
$PN"213"166;
"CA3_B"
$PN"223"165;
"CA4_A"
$PN"70"164;
"CA4_B"
$PN"80"163;
"CA5_A"
$PN"215"162;
"CA5_B"
$PN"225"161;
"CA6_A"
$PN"72"160;
"CA6_B"
$PN"82"159;
"CB6_A"
$PN"203"158;
"CB5_A"
$PN"60"157;
"CB3_A"
$PN"198"156;
"CB2_A"
$PN"196"155;
"CB0_A"
$PN"51"154;
"CB6_B"
$PN"234"153;
"CB5_B"
$PN"91"152;
"CB4_B"
$PN"89"151;
"CB3_B"
$PN"243"150;
"CB2_B"
$PN"241"149;
"CB1_B"
$PN"98"148;
"CB0_B"
$PN"96"26;
"CK_C \B"
$PN"218"147;
"CK_T"
$PN"217"146;
"CS0_A_N"
$PN"64"145;
"CS0_B_N"
$PN"84"144;
"CS1_A_N"
$PN"209"27;
"CS1_B_N"
$PN"229"143;
"DQ30_A"
$PN"192"142;
"DQ29_A"
$PN"49"141;
"DQ28_A"
$PN"47"140;
"DQ27_A"
$PN"187"139;
"DQ26_A"
$PN"185"138;
"DQ25_A"
$PN"42"137;
"DQ24_A"
$PN"40"136;
"DQ23_A"
$PN"183"135;
"DQ22_A"
$PN"181"134;
"DQ21_A"
$PN"38"133;
"DQ20_A"
$PN"36"132;
"DQ19_A"
$PN"176"131;
"DQ18_A"
$PN"174"130;
"DQ17_A"
$PN"31"129;
"DQ16_A"
$PN"29"128;
"DQ15_A"
$PN"172"127;
"DQ14_A"
$PN"170"126;
"DQ13_A"
$PN"27"125;
"DQ12_A"
$PN"25"124;
"DQ11_A"
$PN"165"123;
"DQ10_A"
$PN"163"122;
"DQ9_A"
$PN"20"121;
"DQ8_A"
$PN"18"120;
"DQ7_A"
$PN"161"119;
"DQ6_A"
$PN"159"118;
"DQ5_A"
$PN"16"117;
"DQ4_A"
$PN"14"116;
"DQ3_A"
$PN"154"115;
"DQ2_A"
$PN"152"114;
"DQ1_A"
$PN"9"113;
"DQ0_A"
$PN"7"112;
"DQ31_B"
$PN"287"111;
"DQ30_B"
$PN"285"110;
"DQ29_B"
$PN"142"109;
"DQ28_B"
$PN"140"68;
"DQ27_B"
$PN"280"108;
"DQ26_B"
$PN"278"107;
"DQ25_B"
$PN"135"106;
"DQ24_B"
$PN"133"105;
"DQ23_B"
$PN"276"104;
"DQ22_B"
$PN"274"103;
"DQ21_B"
$PN"131"102;
"DQ20_B"
$PN"129"101;
"DQ19_B"
$PN"269"100;
"DQ18_B"
$PN"267"99;
"DQ17_B"
$PN"124"98;
"DQ16_B"
$PN"122"97;
"DQ15_B"
$PN"265"96;
"DQ14_B"
$PN"263"95;
"DQ13_B"
$PN"120"94;
"DQ12_B"
$PN"118"93;
"DQ11_B"
$PN"258"92;
"DQ10_B"
$PN"256"91;
"DQ9_B"
$PN"113"90;
"DQ8_B"
$PN"111"89;
"DQ7_B"
$PN"254"88;
"DQ6_B"
$PN"252"87;
"DQ5_B"
$PN"109"86;
"DQ4_B"
$PN"107"85;
"DQ3_B"
$PN"247"84;
"DQ2_B"
$PN"245"83;
"DQ1_B"
$PN"102"82;
"DQ0_B"
$PN"100"81;
"HSA"
$PN"148"20;
"HSCL"
$PN"4"22;
"HSDA"
$PN"5"21;
"LBD||RSP_A_N"
$PN"86"80;
"LBS||RSP_B_N"
$PN"87"79;
"PAR_A"
$PN"74"78;
"PAR_B"
$PN"227"77;
"PWR_GOOD||FAIL_N"
$PN"147"76;
"RESET_N \B"
$PN"207"24;
"RFU6"
$PN"232"69;
"RFU5"
$PN"231"75;
"RFU4"
$PN"220"74;
"RFU3"
$PN"150"73;
"RFU2"
$PN"149"72;
"RFU1"
$PN"144"71;
"RFU0"
$PN"2"70;
"VIN_MGMT"
$PN"3"1;
%"TAP"
"1","(-2175,4200)","2","standard","I110";
;
CDS_LIB"standard"
BODY_TYPE"PLUMBING"
HDL_TAP"TRUE";
"B \NAC \NWC"13;
"S \NAC"
BN"3"166;
%"TAP"
"1","(-2175,4250)","2","standard","I111";
;
CDS_LIB"standard"
BODY_TYPE"PLUMBING"
HDL_TAP"TRUE";
"B \NAC \NWC"13;
"S \NAC"
BN"4"164;
%"TAP"
"1","(-2175,4300)","2","standard","I112";
;
CDS_LIB"standard"
BODY_TYPE"PLUMBING"
HDL_TAP"TRUE";
"B \NAC \NWC"13;
"S \NAC"
BN"5"162;
%"TAP"
"1","(-2175,4350)","2","standard","I113";
;
CDS_LIB"standard"
BODY_TYPE"PLUMBING"
HDL_TAP"TRUE";
"B \NAC \NWC"13;
"S \NAC"
BN"6"160;
%"TAP"
"1","(-525,4050)","0","standard","I114";
;
CDS_LIB"standard"
BODY_TYPE"PLUMBING"
HDL_TAP"TRUE";
"B \NAC \NWC"10;
"S \NAC"
BN"25"137;
%"TAP"
"1","(-525,4100)","0","standard","I115";
;
CDS_LIB"standard"
BODY_TYPE"PLUMBING"
HDL_TAP"TRUE";
"B \NAC \NWC"10;
"S \NAC"
BN"26"138;
%"TAP"
"1","(-525,4150)","0","standard","I116";
;
CDS_LIB"standard"
BODY_TYPE"PLUMBING"
HDL_TAP"TRUE";
"B \NAC \NWC"10;
"S \NAC"
BN"27"139;
%"TAP"
"1","(-525,4200)","0","standard","I117";
;
CDS_LIB"standard"
BODY_TYPE"PLUMBING"
HDL_TAP"TRUE";
"B \NAC \NWC"10;
"S \NAC"
BN"28"140;
%"TAP"
"1","(-525,4300)","0","standard","I118";
;
CDS_LIB"standard"
BODY_TYPE"PLUMBING"
HDL_TAP"TRUE";
"B \NAC \NWC"10;
"S \NAC"
BN"30"142;
%"TAP"
"1","(-525,4250)","0","standard","I119";
;
CDS_LIB"standard"
BODY_TYPE"PLUMBING"
HDL_TAP"TRUE";
"B \NAC \NWC"10;
"S \NAC"
BN"29"141;
%"TAP"
"1","(-525,4350)","0","standard","I120";
;
CDS_LIB"standard"
BODY_TYPE"PLUMBING"
HDL_TAP"TRUE";
"B \NAC \NWC"10;
"S \NAC"
BN"31"177;
%"UNIVERSAL_GND"
"1","(1200,100)","0","logical_power","I122";
;
CDS_LIB"logical_power"
HDL_POWER"GND";
"A"9;
%"Q_CAP"
"1","(1200,475)","0","pure_quanta","I123";
;
PART_NUMBER"CH5221MEB00"
PACK_TYPE"C0402"
TOLERANCE"20%"
MATERIAL"X6S"
VOLTAGE"6.3V"
VALUE"2.2UF"
$LOCATION"C38"
CDS_LIB"pure_quanta"
CDS_LOCATION"C38"
$SEC"1"
CDS_SEC"1";
"B"
$PN"2"9;
"A"
$PN"1"4;
%"VCC_CORE"
"1","(1200,800)","0","logical_power","I124";
;
HDL_POWER"P3V3_AUX"
CDS_LIB"logical_power";
"A"4;
%"Q_CAP"
"1","(2200,475)","0","pure_quanta","I125";
;
PART_NUMBER"CH6103KEA00"
TOLERANCE"10%"
PACK_TYPE"C0805"
VOLTAGE"16V"
VALUE"10UF"
MATERIAL"X6S"
$LOCATION"C39"
CDS_LIB"pure_quanta"
CDS_LOCATION"C39"
$SEC"1"
CDS_SEC"1";
"B"
$PN"2"8;
"A"
$PN"1"2;
%"VCC_CORE"
"1","(2200,800)","0","logical_power","I126";
;
HDL_POWER"P12V_S3_AUX_CPU0_NVDIMM"
CDS_LIB"logical_power";
"A"2;
%"TAP"
"1","(2225,2400)","0","standard","I128";
;
CDS_LIB"standard"
BODY_TYPE"PLUMBING"
HDL_TAP"TRUE";
"B \NAC \NWC"16;
"S \NAC"
BN"0"66;
%"TAP"
"1","(2225,2500)","0","standard","I129";
;
CDS_LIB"standard"
BODY_TYPE"PLUMBING"
HDL_TAP"TRUE";
"B \NAC \NWC"16;
"S \NAC"
BN"1"67;
%"TAP"
"1","(2400,2350)","0","standard","I130";
;
CDS_LIB"standard"
BODY_TYPE"PLUMBING"
HDL_TAP"TRUE";
"B \NAC \NWC"18;
"S \NAC"
BN"0"47;
%"TAP"
"1","(2400,2450)","0","standard","I131";
;
CDS_LIB"standard"
BODY_TYPE"PLUMBING"
HDL_TAP"TRUE";
"B \NAC \NWC"18;
"S \NAC"
BN"1"48;
%"TAP"
"1","(2225,2600)","0","standard","I132";
;
CDS_LIB"standard"
BODY_TYPE"PLUMBING"
HDL_TAP"TRUE";
"B \NAC \NWC"16;
"S \NAC"
BN"2"28;
%"TAP"
"1","(2225,2700)","0","standard","I133";
;
CDS_LIB"standard"
BODY_TYPE"PLUMBING"
HDL_TAP"TRUE";
"B \NAC \NWC"16;
"S \NAC"
BN"3"65;
%"TAP"
"1","(2400,2550)","0","standard","I134";
;
CDS_LIB"standard"
BODY_TYPE"PLUMBING"
HDL_TAP"TRUE";
"B \NAC \NWC"18;
"S \NAC"
BN"2"29;
%"TAP"
"1","(2400,2750)","0","standard","I135";
;
CDS_LIB"standard"
BODY_TYPE"PLUMBING"
HDL_TAP"TRUE";
"B \NAC \NWC"18;
"S \NAC"
BN"4"46;
%"TAP"
"1","(2400,2650)","0","standard","I136";
;
CDS_LIB"standard"
BODY_TYPE"PLUMBING"
HDL_TAP"TRUE";
"B \NAC \NWC"18;
"S \NAC"
BN"3"45;
%"TAP"
"1","(2225,2800)","0","standard","I137";
;
CDS_LIB"standard"
BODY_TYPE"PLUMBING"
HDL_TAP"TRUE";
"B \NAC \NWC"16;
"S \NAC"
BN"4"64;
%"TAP"
"1","(2225,3000)","0","standard","I138";
;
CDS_LIB"standard"
BODY_TYPE"PLUMBING"
HDL_TAP"TRUE";
"B \NAC \NWC"16;
"S \NAC"
BN"6"62;
%"TAP"
"1","(2225,2900)","0","standard","I139";
;
CDS_LIB"standard"
BODY_TYPE"PLUMBING"
HDL_TAP"TRUE";
"B \NAC \NWC"16;
"S \NAC"
BN"5"63;
%"TAP"
"1","(2400,2850)","0","standard","I140";
;
CDS_LIB"standard"
BODY_TYPE"PLUMBING"
HDL_TAP"TRUE";
"B \NAC \NWC"18;
"S \NAC"
BN"5"44;
%"TAP"
"1","(2400,2950)","0","standard","I141";
;
CDS_LIB"standard"
BODY_TYPE"PLUMBING"
HDL_TAP"TRUE";
"B \NAC \NWC"18;
"S \NAC"
BN"6"42;
%"TAP"
"1","(2225,3100)","0","standard","I142";
;
CDS_LIB"standard"
BODY_TYPE"PLUMBING"
HDL_TAP"TRUE";
"B \NAC \NWC"16;
"S \NAC"
BN"7"59;
%"TAP"
"1","(2225,3200)","0","standard","I143";
;
CDS_LIB"standard"
BODY_TYPE"PLUMBING"
HDL_TAP"TRUE";
"B \NAC \NWC"16;
"S \NAC"
BN"8"60;
%"TAP"
"1","(2400,3050)","0","standard","I144";
;
CDS_LIB"standard"
BODY_TYPE"PLUMBING"
HDL_TAP"TRUE";
"B \NAC \NWC"18;
"S \NAC"
BN"7"43;
%"TAP"
"1","(2400,3150)","0","standard","I145";
;
CDS_LIB"standard"
BODY_TYPE"PLUMBING"
HDL_TAP"TRUE";
"B \NAC \NWC"18;
"S \NAC"
BN"8"40;
%"TAP"
"1","(2400,3250)","0","standard","I146";
;
CDS_LIB"standard"
BODY_TYPE"PLUMBING"
HDL_TAP"TRUE";
"B \NAC \NWC"18;
"S \NAC"
BN"9"41;
%"TAP"
"1","(2225,3300)","0","standard","I147";
;
CDS_LIB"standard"
BODY_TYPE"PLUMBING"
HDL_TAP"TRUE";
"B \NAC \NWC"16;
"S \NAC"
BN"9"61;
%"TAP"
"1","(2225,3450)","0","standard","I148";
;
CDS_LIB"standard"
BODY_TYPE"PLUMBING"
HDL_TAP"TRUE";
"B \NAC \NWC"17;
"S \NAC"
BN"0"57;
%"TAP"
"1","(2400,3400)","0","standard","I149";
;
CDS_LIB"standard"
BODY_TYPE"PLUMBING"
HDL_TAP"TRUE";
"B \NAC \NWC"19;
"S \NAC"
BN"0"39;
%"TAP"
"1","(2400,3500)","0","standard","I150";
;
CDS_LIB"standard"
BODY_TYPE"PLUMBING"
HDL_TAP"TRUE";
"B \NAC \NWC"19;
"S \NAC"
BN"1"38;
%"TAP"
"1","(2225,3650)","0","standard","I151";
;
CDS_LIB"standard"
BODY_TYPE"PLUMBING"
HDL_TAP"TRUE";
"B \NAC \NWC"17;
"S \NAC"
BN"2"55;
%"TAP"
"1","(2225,3550)","0","standard","I152";
;
CDS_LIB"standard"
BODY_TYPE"PLUMBING"
HDL_TAP"TRUE";
"B \NAC \NWC"17;
"S \NAC"
BN"1"58;
%"TAP"
"1","(2225,3750)","0","standard","I153";
;
CDS_LIB"standard"
BODY_TYPE"PLUMBING"
HDL_TAP"TRUE";
"B \NAC \NWC"17;
"S \NAC"
BN"3"56;
%"TAP"
"1","(2400,3600)","0","standard","I154";
;
CDS_LIB"standard"
BODY_TYPE"PLUMBING"
HDL_TAP"TRUE";
"B \NAC \NWC"19;
"S \NAC"
BN"2"37;
%"TAP"
"1","(2400,3700)","0","standard","I155";
;
CDS_LIB"standard"
BODY_TYPE"PLUMBING"
HDL_TAP"TRUE";
"B \NAC \NWC"19;
"S \NAC"
BN"3"36;
%"TAP"
"1","(2225,3850)","0","standard","I156";
;
CDS_LIB"standard"
BODY_TYPE"PLUMBING"
HDL_TAP"TRUE";
"B \NAC \NWC"17;
"S \NAC"
BN"4"52;
%"TAP"
"1","(2225,3950)","0","standard","I157";
;
CDS_LIB"standard"
BODY_TYPE"PLUMBING"
HDL_TAP"TRUE";
"B \NAC \NWC"17;
"S \NAC"
BN"5"53;
%"TAP"
"1","(2400,3900)","0","standard","I158";
;
CDS_LIB"standard"
BODY_TYPE"PLUMBING"
HDL_TAP"TRUE";
"B \NAC \NWC"19;
"S \NAC"
BN"5"33;
%"TAP"
"1","(2400,3800)","0","standard","I159";
;
CDS_LIB"standard"
BODY_TYPE"PLUMBING"
HDL_TAP"TRUE";
"B \NAC \NWC"19;
"S \NAC"
BN"4"35;
%"VCC_CORE"
"1","(-3000,2225)","0","logical_power","I16";
;
HDL_POWER"P3V3_AUX"
CDS_LIB"logical_power";
"A"1;
%"TAP"
"1","(2400,4000)","0","standard","I160";
;
CDS_LIB"standard"
BODY_TYPE"PLUMBING"
HDL_TAP"TRUE";
"B \NAC \NWC"19;
"S \NAC"
BN"6"34;
%"UNIVERSAL_GND"
"1","(2825,100)","0","logical_power","I161";
;
CDS_LIB"logical_power"
HDL_POWER"GND";
"A"8;
%"Q_CAP"
"1","(2825,475)","0","pure_quanta","I162";
;
PART_NUMBER"CH6103KEA00"
TOLERANCE"10%"
VOLTAGE"16V"
VALUE"10UF"
PACK_TYPE"C0805"
MATERIAL"X6S"
$LOCATION"C40"
CDS_LIB"pure_quanta"
CDS_LOCATION"C40"
$SEC"1"
CDS_SEC"1";
"B"
$PN"2"8;
"A"
$PN"1"2;
%"UNIVERSAL_GND"
"1","(3900,650)","0","logical_power","I163";
;
CDS_LIB"logical_power"
HDL_POWER"GND";
"A"7;
%"SCONN288_ADR50017P130CC"
"3","(4750,2725)","0","pure_quanta","I164";
;
PART_NUMBER"DFHST8FS461"
MATERIAL"IO"
PART_TYPE"SMLF"
VALUE"SCONN288_ADR50017-P130CC"
$LOCATION"J13"
NEEDS_NO_SIZE"TRUE"
CDS_LMAN_SYM_OUTLINE"-450,1775,450,-1775"
CDS_LIB"pure_quanta"
CDS_LOCATION"J13"
$SEC"3"
CDS_SEC"3";
"G3"
$PN"G3"6;
"G2"
$PN"G2"6;
"G1"
$PN"G1"6;
"VSS62"
$PN"141"6;
"VSS61"
$PN"139"6;
"VSS60"
$PN"136"6;
"VSS58"
$PN"132"6;
"VSS104"
$PN"240"7;
"VSS102"
$PN"235"7;
"VSS100"
$PN"230"7;
"VIN_BULK2"
$PN"146"3;
"VIN_BULK1"
$PN"145"3;
"VIN_BULK0"
$PN"1"3;
"VSS126"
$PN"288"7;
"VSS125"
$PN"286"7;
"VSS124"
$PN"284"7;
"VSS123"
$PN"281"7;
"VSS122"
$PN"279"7;
"VSS121"
$PN"277"7;
"VSS120"
$PN"275"7;
"VSS119"
$PN"273"7;
"VSS118"
$PN"270"7;
"VSS117"
$PN"268"7;
"VSS116"
$PN"266"7;
"VSS115"
$PN"264"7;
"VSS114"
$PN"262"7;
"VSS113"
$PN"259"7;
"VSS112"
$PN"257"7;
"VSS111"
$PN"255"7;
"VSS110"
$PN"253"7;
"VSS109"
$PN"251"7;
"VSS108"
$PN"248"7;
"VSS107"
$PN"246"7;
"VSS106"
$PN"244"7;
"VSS105"
$PN"242"7;
"VSS103"
$PN"237"7;
"VSS101"
$PN"233"7;
"VSS99"
$PN"228"7;
"VSS98"
$PN"226"7;
"VSS97"
$PN"224"7;
"VSS96"
$PN"222"7;
"VSS95"
$PN"219"7;
"VSS94"
$PN"216"7;
"VSS93"
$PN"214"7;
"VSS92"
$PN"212"7;
"VSS91"
$PN"210"7;
"VSS90"
$PN"208"7;
"VSS89"
$PN"206"7;
"VSS88"
$PN"204"7;
"VSS87"
$PN"202"7;
"VSS86"
$PN"199"7;
"VSS85"
$PN"197"7;
"VSS84"
$PN"195"7;
"VSS83"
$PN"193"7;
"VSS82"
$PN"191"7;
"VSS81"
$PN"188"7;
"VSS80"
$PN"186"7;
"VSS79"
$PN"184"7;
"VSS78"
$PN"182"7;
"VSS77"
$PN"180"7;
"VSS76"
$PN"177"7;
"VSS75"
$PN"175"7;
"VSS74"
$PN"173"7;
"VSS73"
$PN"171"7;
"VSS72"
$PN"169"7;
"VSS71"
$PN"166"7;
"VSS70"
$PN"164"7;
"VSS69"
$PN"162"7;
"VSS68"
$PN"160"7;
"VSS67"
$PN"158"7;
"VSS66"
$PN"155"7;
"VSS65"
$PN"153"7;
"VSS64"
$PN"151"7;
"VSS63"
$PN"143"6;
"VSS59"
$PN"134"6;
"VSS57"
$PN"130"6;
"VSS56"
$PN"128"6;
"VSS55"
$PN"125"6;
"VSS54"
$PN"123"6;
"VSS53"
$PN"121"6;
"VSS52"
$PN"119"6;
"VSS51"
$PN"117"6;
"VSS50"
$PN"114"6;
"VSS49"
$PN"112"6;
"VSS48"
$PN"110"6;
"VSS47"
$PN"108"6;
"VSS46"
$PN"106"6;
"VSS45"
$PN"103"6;
"VSS44"
$PN"101"6;
"VSS43"
$PN"99"6;
"VSS42"
$PN"97"6;
"VSS41"
$PN"95"6;
"VSS40"
$PN"92"6;
"VSS39"
$PN"90"6;
"VSS38"
$PN"88"6;
"VSS37"
$PN"85"6;
"VSS36"
$PN"83"6;
"VSS35"
$PN"81"6;
"VSS34"
$PN"79"6;
"VSS33"
$PN"77"6;
"VSS32"
$PN"75"6;
"VSS31"
$PN"73"6;
"VSS30"
$PN"71"6;
"VSS29"
$PN"69"6;
"VSS28"
$PN"67"6;
"VSS27"
$PN"65"6;
"VSS26"
$PN"63"6;
"VSS25"
$PN"61"6;
"VSS24"
$PN"59"6;
"VSS23"
$PN"57"6;
"VSS22"
$PN"54"6;
"VSS21"
$PN"52"6;
"VSS20"
$PN"50"6;
"VSS19"
$PN"48"6;
"VSS18"
$PN"46"6;
"VSS17"
$PN"43"6;
"VSS16"
$PN"41"6;
"VSS15"
$PN"39"6;
"VSS14"
$PN"37"6;
"VSS13"
$PN"35"6;
"VSS12"
$PN"32"6;
"VSS11"
$PN"30"6;
"VSS10"
$PN"28"6;
"VSS9"
$PN"26"6;
"VSS8"
$PN"24"6;
"VSS7"
$PN"21"6;
"VSS6"
$PN"19"6;
"VSS5"
$PN"17"6;
"VSS4"
$PN"15"6;
"VSS3"
$PN"13"6;
"VSS2"
$PN"10"6;
"VSS1"
$PN"8"6;
"VSS0"
$PN"6"6;
%"TAP"
"1","(2225,4150)","0","standard","I167";
;
CDS_LIB"standard"
BODY_TYPE"PLUMBING"
HDL_TAP"TRUE";
"B \NAC \NWC"17;
"S \NAC"
BN"7"50;
%"TAP"
"1","(2225,4050)","0","standard","I168";
;
CDS_LIB"standard"
BODY_TYPE"PLUMBING"
HDL_TAP"TRUE";
"B \NAC \NWC"17;
"S \NAC"
BN"6"54;
%"TAP"
"1","(2225,4250)","0","standard","I169";
;
CDS_LIB"standard"
BODY_TYPE"PLUMBING"
HDL_TAP"TRUE";
"B \NAC \NWC"17;
"S \NAC"
BN"8"51;
%"TAP"
"1","(2400,4100)","0","standard","I170";
;
CDS_LIB"standard"
BODY_TYPE"PLUMBING"
HDL_TAP"TRUE";
"B \NAC \NWC"19;
"S \NAC"
BN"7"30;
%"TAP"
"1","(2400,4200)","0","standard","I171";
;
CDS_LIB"standard"
BODY_TYPE"PLUMBING"
HDL_TAP"TRUE";
"B \NAC \NWC"19;
"S \NAC"
BN"8"31;
%"TAP"
"1","(2400,4300)","0","standard","I172";
;
CDS_LIB"standard"
BODY_TYPE"PLUMBING"
HDL_TAP"TRUE";
"B \NAC \NWC"19;
"S \NAC"
BN"9"32;
%"TAP"
"1","(2225,4350)","0","standard","I173";
;
CDS_LIB"standard"
BODY_TYPE"PLUMBING"
HDL_TAP"TRUE";
"B \NAC \NWC"17;
"S \NAC"
BN"9"49;
%"VCC_CORE"
"1","(3900,4900)","0","logical_power","I176";
;
HDL_POWER"P12V_S3_AUX_CPU0_NVDIMM"
CDS_LIB"logical_power";
"A"3;
%"UNIVERSAL_GND"
"1","(5600,650)","0","logical_power","I177";
;
CDS_LIB"logical_power"
HDL_POWER"GND";
"A"6;
%"SCONN288_ADR50017P130CC"
"2","(1325,3350)","0","pure_quanta","I178";
;
PART_NUMBER"DFHST8FS461"
MATERIAL"IO"
VALUE"SCONN288_ADR50017-P130CC"
PART_TYPE"SMLF"
LOCATION"J13"
NEEDS_NO_SIZE"TRUE"
CDS_LMAN_SYM_OUTLINE"-600,1150,600,-1150"
CDS_LIB"pure_quanta"
$SEC"2"
CDS_SEC"2";
"DQS7_A_C||TDQS7_A_C \B"
$PN"178"30;
"DQS6_A_T||TDQS6_A_T"
$PN"168"54;
"DQS8_B_T||TDQS8_B_T"
$PN"283"60;
"DQS8_B_C||TDQS8_B_C \B"
$PN"282"40;
"DQS7_B_T||TDQS7_B_T"
$PN"272"59;
"DQS0_A_C \B"
$PN"12"39;
"DQS0_A_T"
$PN"11"57;
"DQS0_B_C \B"
$PN"105"47;
"DQS0_B_T"
$PN"104"66;
"DQS1_A_C \B"
$PN"23"38;
"DQS1_A_T"
$PN"22"58;
"DQS1_B_C \B"
$PN"116"48;
"DQS1_B_T"
$PN"115"67;
"DQS2_A_C \B"
$PN"34"37;
"DQS2_A_T"
$PN"33"55;
"DQS2_B_C \B"
$PN"127"29;
"DQS2_B_T"
$PN"126"28;
"DQS3_A_C \B"
$PN"45"36;
"DQS3_A_T"
$PN"44"56;
"DQS3_B_C \B"
$PN"138"45;
"DQS3_B_T"
$PN"137"65;
"DQS4_A_C \B"
$PN"56"35;
"DQS4_A_T"
$PN"55"52;
"DQS4_B_C \B"
$PN"238"46;
"DQS4_B_T"
$PN"239"64;
"DQS5_A_C||TDQS5_A_C||DQS5_A_T||TDQS5_A_T \B"
$PN"156"33;
"DQS5_A_T||TDQS5_A_T"
$PN"157"53;
"DQS5_B_C||TDQS5_B_C \B"
$PN"249"44;
"DQS5_B_T||TDQS5_B_T"
$PN"250"63;
"DQS6_A_C||TDQS6_A_C||DQS6_A_T||TDQS6_A_T \B"
$PN"167"34;
"DQS6_B_C||TDQS6_B_C \B"
$PN"260"42;
"DQS6_B_T||TDQS6_B_T"
$PN"261"62;
"DQS7_A_T||TDQS7_A_T"
$PN"179"50;
"DQS7_B_C||TDQS7_B_C \B"
$PN"271"43;
"DQS8_A_C||TDQS8_A_C \B"
$PN"189"31;
"DQS8_A_T||TDQS8_A_T"
$PN"190"51;
"DQS9_A_C||TDQS9_A_C \B"
$PN"200"32;
"DQS9_A_T||TDQS9_A_T"
$PN"201"49;
"DQS9_B_C||TDQS9_B_C \B"
$PN"94"41;
"DQS9_B_T||TDQS9_B_T||DBI4_B_N"
$PN"93"61;
%"Q_RES"
"1","(-3150,1650)","0","pure_quanta","I179";
;
PART_NUMBER"CS04992FB07"
VALUE"49.9"
MATERIAL"CHIP"
$LOCATION"R3887"
CDS_LIB"pure_quanta"
PACK_TYPE"0402LF"
TOLERANCE"1%"
WATTAGE"1/16W"
CDS_LOCATION"R3887"
$SEC"1"
CDS_SEC"1";
"B"
$PN"2"25;
"A"
$PN"1"22;
%"TAP"
"1","(-2175,2150)","2","standard","I25";
;
CDS_LIB"standard"
BODY_TYPE"PLUMBING"
HDL_TAP"TRUE";
"B \NAC \NWC"12;
"S \NAC"
BN"0"26;
%"TAP"
"1","(-2175,2200)","2","standard","I26";
;
CDS_LIB"standard"
BODY_TYPE"PLUMBING"
HDL_TAP"TRUE";
"B \NAC \NWC"12;
"S \NAC"
BN"1"148;
%"TAP"
"1","(-2175,2250)","2","standard","I27";
;
CDS_LIB"standard"
BODY_TYPE"PLUMBING"
HDL_TAP"TRUE";
"B \NAC \NWC"12;
"S \NAC"
BN"2"149;
%"TAP"
"1","(-2175,2300)","2","standard","I28";
;
CDS_LIB"standard"
BODY_TYPE"PLUMBING"
HDL_TAP"TRUE";
"B \NAC \NWC"12;
"S \NAC"
BN"3"150;
%"TAP"
"1","(-2175,2350)","2","standard","I29";
;
CDS_LIB"standard"
BODY_TYPE"PLUMBING"
HDL_TAP"TRUE";
"B \NAC \NWC"12;
"S \NAC"
BN"4"151;
%"TAP"
"1","(-2175,2450)","2","standard","I30";
;
CDS_LIB"standard"
BODY_TYPE"PLUMBING"
HDL_TAP"TRUE";
"B \NAC \NWC"12;
"S \NAC"
BN"6"153;
%"TAP"
"1","(-2175,2400)","2","standard","I31";
;
CDS_LIB"standard"
BODY_TYPE"PLUMBING"
HDL_TAP"TRUE";
"B \NAC \NWC"12;
"S \NAC"
BN"5"152;
%"TAP"
"1","(-2175,2500)","2","standard","I32";
;
CDS_LIB"standard"
BODY_TYPE"PLUMBING"
HDL_TAP"TRUE";
"B \NAC \NWC"12;
"S \NAC"
BN"7"173;
%"TAP"
"1","(-2175,2600)","2","standard","I33";
;
CDS_LIB"standard"
BODY_TYPE"PLUMBING"
HDL_TAP"TRUE";
"B \NAC \NWC"11;
"S \NAC"
BN"0"154;
%"TAP"
"1","(-2175,2650)","2","standard","I34";
;
CDS_LIB"standard"
BODY_TYPE"PLUMBING"
HDL_TAP"TRUE";
"B \NAC \NWC"11;
"S \NAC"
BN"1"174;
%"TAP"
"1","(-2175,2700)","2","standard","I35";
;
CDS_LIB"standard"
BODY_TYPE"PLUMBING"
HDL_TAP"TRUE";
"B \NAC \NWC"11;
"S \NAC"
BN"2"155;
%"TAP"
"1","(-2175,2750)","2","standard","I36";
;
CDS_LIB"standard"
BODY_TYPE"PLUMBING"
HDL_TAP"TRUE";
"B \NAC \NWC"11;
"S \NAC"
BN"3"156;
%"TAP"
"1","(-2175,2850)","2","standard","I37";
;
CDS_LIB"standard"
BODY_TYPE"PLUMBING"
HDL_TAP"TRUE";
"B \NAC \NWC"11;
"S \NAC"
BN"5"157;
%"TAP"
"1","(-2175,2800)","2","standard","I38";
;
CDS_LIB"standard"
BODY_TYPE"PLUMBING"
HDL_TAP"TRUE";
"B \NAC \NWC"11;
"S \NAC"
BN"4"175;
%"TAP"
"1","(-2175,2950)","2","standard","I39";
;
CDS_LIB"standard"
BODY_TYPE"PLUMBING"
HDL_TAP"TRUE";
"B \NAC \NWC"11;
"S \NAC"
BN"7"176;
%"TAP"
"1","(-2175,2900)","2","standard","I40";
;
CDS_LIB"standard"
BODY_TYPE"PLUMBING"
HDL_TAP"TRUE";
"B \NAC \NWC"11;
"S \NAC"
BN"6"158;
%"TAP"
"1","(-2175,3650)","2","standard","I41";
;
CDS_LIB"standard"
BODY_TYPE"PLUMBING"
HDL_TAP"TRUE";
"B \NAC \NWC"14;
"S \NAC"
BN"0"171;
%"TAP"
"1","(-2175,3700)","2","standard","I42";
;
CDS_LIB"standard"
BODY_TYPE"PLUMBING"
HDL_TAP"TRUE";
"B \NAC \NWC"14;
"S \NAC"
BN"1"169;
%"TAP"
"1","(-2175,3750)","2","standard","I43";
;
CDS_LIB"standard"
BODY_TYPE"PLUMBING"
HDL_TAP"TRUE";
"B \NAC \NWC"14;
"S \NAC"
BN"2"167;
%"TAP"
"1","(-2175,3800)","2","standard","I44";
;
CDS_LIB"standard"
BODY_TYPE"PLUMBING"
HDL_TAP"TRUE";
"B \NAC \NWC"14;
"S \NAC"
BN"3"165;
%"TAP"
"1","(-2175,3850)","2","standard","I45";
;
CDS_LIB"standard"
BODY_TYPE"PLUMBING"
HDL_TAP"TRUE";
"B \NAC \NWC"14;
"S \NAC"
BN"4"163;
%"TAP"
"1","(-2175,3900)","2","standard","I46";
;
CDS_LIB"standard"
BODY_TYPE"PLUMBING"
HDL_TAP"TRUE";
"B \NAC \NWC"14;
"S \NAC"
BN"5"161;
%"TAP"
"1","(-2175,3950)","2","standard","I47";
;
CDS_LIB"standard"
BODY_TYPE"PLUMBING"
HDL_TAP"TRUE";
"B \NAC \NWC"14;
"S \NAC"
BN"6"159;
%"TAP"
"1","(-525,1200)","0","standard","I48";
;
CDS_LIB"standard"
BODY_TYPE"PLUMBING"
HDL_TAP"TRUE";
"B \NAC \NWC"15;
"S \NAC"
BN"1"82;
%"TAP"
"1","(-525,1150)","0","standard","I49";
;
CDS_LIB"standard"
BODY_TYPE"PLUMBING"
HDL_TAP"TRUE";
"B \NAC \NWC"15;
"S \NAC"
BN"0"81;
%"TAP"
"1","(-525,1250)","0","standard","I50";
;
CDS_LIB"standard"
BODY_TYPE"PLUMBING"
HDL_TAP"TRUE";
"B \NAC \NWC"15;
"S \NAC"
BN"2"83;
%"TAP"
"1","(-525,1350)","0","standard","I51";
;
CDS_LIB"standard"
BODY_TYPE"PLUMBING"
HDL_TAP"TRUE";
"B \NAC \NWC"15;
"S \NAC"
BN"4"85;
%"TAP"
"1","(-525,1300)","0","standard","I52";
;
CDS_LIB"standard"
BODY_TYPE"PLUMBING"
HDL_TAP"TRUE";
"B \NAC \NWC"15;
"S \NAC"
BN"3"84;
%"TAP"
"1","(-525,1450)","0","standard","I53";
;
CDS_LIB"standard"
BODY_TYPE"PLUMBING"
HDL_TAP"TRUE";
"B \NAC \NWC"15;
"S \NAC"
BN"6"87;
%"TAP"
"1","(-525,1400)","0","standard","I54";
;
CDS_LIB"standard"
BODY_TYPE"PLUMBING"
HDL_TAP"TRUE";
"B \NAC \NWC"15;
"S \NAC"
BN"5"86;
%"TAP"
"1","(-525,1500)","0","standard","I55";
;
CDS_LIB"standard"
BODY_TYPE"PLUMBING"
HDL_TAP"TRUE";
"B \NAC \NWC"15;
"S \NAC"
BN"7"88;
%"TAP"
"1","(-525,1550)","0","standard","I56";
;
CDS_LIB"standard"
BODY_TYPE"PLUMBING"
HDL_TAP"TRUE";
"B \NAC \NWC"15;
"S \NAC"
BN"8"89;
%"TAP"
"1","(-525,1600)","0","standard","I57";
;
CDS_LIB"standard"
BODY_TYPE"PLUMBING"
HDL_TAP"TRUE";
"B \NAC \NWC"15;
"S \NAC"
BN"9"90;
%"TAP"
"1","(-525,1700)","0","standard","I58";
;
CDS_LIB"standard"
BODY_TYPE"PLUMBING"
HDL_TAP"TRUE";
"B \NAC \NWC"15;
"S \NAC"
BN"11"92;
%"TAP"
"1","(-525,1650)","0","standard","I59";
;
CDS_LIB"standard"
BODY_TYPE"PLUMBING"
HDL_TAP"TRUE";
"B \NAC \NWC"15;
"S \NAC"
BN"10"91;
%"TAP"
"1","(-525,1750)","0","standard","I60";
;
CDS_LIB"standard"
BODY_TYPE"PLUMBING"
HDL_TAP"TRUE";
"B \NAC \NWC"15;
"S \NAC"
BN"12"93;
%"TAP"
"1","(-525,1800)","0","standard","I61";
;
CDS_LIB"standard"
BODY_TYPE"PLUMBING"
HDL_TAP"TRUE";
"B \NAC \NWC"15;
"S \NAC"
BN"13"94;
%"TAP"
"1","(-525,1850)","0","standard","I62";
;
CDS_LIB"standard"
BODY_TYPE"PLUMBING"
HDL_TAP"TRUE";
"B \NAC \NWC"15;
"S \NAC"
BN"14"95;
%"TAP"
"1","(-525,1950)","0","standard","I63";
;
CDS_LIB"standard"
BODY_TYPE"PLUMBING"
HDL_TAP"TRUE";
"B \NAC \NWC"15;
"S \NAC"
BN"16"97;
%"TAP"
"1","(-525,1900)","0","standard","I64";
;
CDS_LIB"standard"
BODY_TYPE"PLUMBING"
HDL_TAP"TRUE";
"B \NAC \NWC"15;
"S \NAC"
BN"15"96;
%"TAP"
"1","(-525,2000)","0","standard","I65";
;
CDS_LIB"standard"
BODY_TYPE"PLUMBING"
HDL_TAP"TRUE";
"B \NAC \NWC"15;
"S \NAC"
BN"17"98;
%"TAP"
"1","(-525,2050)","0","standard","I66";
;
CDS_LIB"standard"
BODY_TYPE"PLUMBING"
HDL_TAP"TRUE";
"B \NAC \NWC"15;
"S \NAC"
BN"18"99;
%"TAP"
"1","(-525,2100)","0","standard","I67";
;
CDS_LIB"standard"
BODY_TYPE"PLUMBING"
HDL_TAP"TRUE";
"B \NAC \NWC"15;
"S \NAC"
BN"19"100;
%"TAP"
"1","(-525,2150)","0","standard","I68";
;
CDS_LIB"standard"
BODY_TYPE"PLUMBING"
HDL_TAP"TRUE";
"B \NAC \NWC"15;
"S \NAC"
BN"20"101;
%"TAP"
"1","(-525,2250)","0","standard","I69";
;
CDS_LIB"standard"
BODY_TYPE"PLUMBING"
HDL_TAP"TRUE";
"B \NAC \NWC"15;
"S \NAC"
BN"22"103;
%"TAP"
"1","(-525,2200)","0","standard","I70";
;
CDS_LIB"standard"
BODY_TYPE"PLUMBING"
HDL_TAP"TRUE";
"B \NAC \NWC"15;
"S \NAC"
BN"21"102;
%"TAP"
"1","(-525,2350)","0","standard","I71";
;
CDS_LIB"standard"
BODY_TYPE"PLUMBING"
HDL_TAP"TRUE";
"B \NAC \NWC"15;
"S \NAC"
BN"24"105;
%"TAP"
"1","(-525,2300)","0","standard","I72";
;
CDS_LIB"standard"
BODY_TYPE"PLUMBING"
HDL_TAP"TRUE";
"B \NAC \NWC"15;
"S \NAC"
BN"23"104;
%"TAP"
"1","(-525,2400)","0","standard","I73";
;
CDS_LIB"standard"
BODY_TYPE"PLUMBING"
HDL_TAP"TRUE";
"B \NAC \NWC"15;
"S \NAC"
BN"25"106;
%"TAP"
"1","(-525,2450)","0","standard","I74";
;
CDS_LIB"standard"
BODY_TYPE"PLUMBING"
HDL_TAP"TRUE";
"B \NAC \NWC"15;
"S \NAC"
BN"26"107;
%"TAP"
"1","(-525,2500)","0","standard","I75";
;
CDS_LIB"standard"
BODY_TYPE"PLUMBING"
HDL_TAP"TRUE";
"B \NAC \NWC"15;
"S \NAC"
BN"27"108;
%"TAP"
"1","(-525,2600)","0","standard","I76";
;
CDS_LIB"standard"
BODY_TYPE"PLUMBING"
HDL_TAP"TRUE";
"B \NAC \NWC"15;
"S \NAC"
BN"29"109;
%"TAP"
"1","(-525,2550)","0","standard","I77";
;
CDS_LIB"standard"
BODY_TYPE"PLUMBING"
HDL_TAP"TRUE";
"B \NAC \NWC"15;
"S \NAC"
BN"28"68;
%"TAP"
"1","(-525,2700)","0","standard","I78";
;
CDS_LIB"standard"
BODY_TYPE"PLUMBING"
HDL_TAP"TRUE";
"B \NAC \NWC"15;
"S \NAC"
BN"31"111;
%"TAP"
"1","(-525,2650)","0","standard","I79";
;
CDS_LIB"standard"
BODY_TYPE"PLUMBING"
HDL_TAP"TRUE";
"B \NAC \NWC"15;
"S \NAC"
BN"30"110;
%"TAP"
"1","(-525,2800)","0","standard","I80";
;
CDS_LIB"standard"
BODY_TYPE"PLUMBING"
HDL_TAP"TRUE";
"B \NAC \NWC"10;
"S \NAC"
BN"0"112;
%"TAP"
"1","(-525,2850)","0","standard","I81";
;
CDS_LIB"standard"
BODY_TYPE"PLUMBING"
HDL_TAP"TRUE";
"B \NAC \NWC"10;
"S \NAC"
BN"1"113;
%"TAP"
"1","(-525,2950)","0","standard","I82";
;
CDS_LIB"standard"
BODY_TYPE"PLUMBING"
HDL_TAP"TRUE";
"B \NAC \NWC"10;
"S \NAC"
BN"3"115;
%"TAP"
"1","(-525,2900)","0","standard","I83";
;
CDS_LIB"standard"
BODY_TYPE"PLUMBING"
HDL_TAP"TRUE";
"B \NAC \NWC"10;
"S \NAC"
BN"2"114;
%"TAP"
"1","(-525,3000)","0","standard","I84";
;
CDS_LIB"standard"
BODY_TYPE"PLUMBING"
HDL_TAP"TRUE";
"B \NAC \NWC"10;
"S \NAC"
BN"4"116;
%"TAP"
"1","(-525,3100)","0","standard","I85";
;
CDS_LIB"standard"
BODY_TYPE"PLUMBING"
HDL_TAP"TRUE";
"B \NAC \NWC"10;
"S \NAC"
BN"6"118;
%"TAP"
"1","(-525,3050)","0","standard","I86";
;
CDS_LIB"standard"
BODY_TYPE"PLUMBING"
HDL_TAP"TRUE";
"B \NAC \NWC"10;
"S \NAC"
BN"5"117;
%"TAP"
"1","(-525,3150)","0","standard","I87";
;
CDS_LIB"standard"
BODY_TYPE"PLUMBING"
HDL_TAP"TRUE";
"B \NAC \NWC"10;
"S \NAC"
BN"7"119;
%"TAP"
"1","(-525,3250)","0","standard","I88";
;
CDS_LIB"standard"
BODY_TYPE"PLUMBING"
HDL_TAP"TRUE";
"B \NAC \NWC"10;
"S \NAC"
BN"9"121;
%"TAP"
"1","(-525,3200)","0","standard","I89";
;
CDS_LIB"standard"
BODY_TYPE"PLUMBING"
HDL_TAP"TRUE";
"B \NAC \NWC"10;
"S \NAC"
BN"8"120;
%"UNIVERSAL_GND"
"1","(-1950,-25)","0","logical_power","I9";
;
CDS_LIB"logical_power"
HDL_POWER"GND";
"A"5;
%"TAP"
"1","(-525,3300)","0","standard","I90";
;
CDS_LIB"standard"
BODY_TYPE"PLUMBING"
HDL_TAP"TRUE";
"B \NAC \NWC"10;
"S \NAC"
BN"10"122;
%"TAP"
"1","(-525,3350)","0","standard","I91";
;
CDS_LIB"standard"
BODY_TYPE"PLUMBING"
HDL_TAP"TRUE";
"B \NAC \NWC"10;
"S \NAC"
BN"11"123;
%"TAP"
"1","(-525,3400)","0","standard","I92";
;
CDS_LIB"standard"
BODY_TYPE"PLUMBING"
HDL_TAP"TRUE";
"B \NAC \NWC"10;
"S \NAC"
BN"12"124;
%"TAP"
"1","(-525,3500)","0","standard","I93";
;
CDS_LIB"standard"
BODY_TYPE"PLUMBING"
HDL_TAP"TRUE";
"B \NAC \NWC"10;
"S \NAC"
BN"14"126;
%"TAP"
"1","(-525,3450)","0","standard","I94";
;
CDS_LIB"standard"
BODY_TYPE"PLUMBING"
HDL_TAP"TRUE";
"B \NAC \NWC"10;
"S \NAC"
BN"13"125;
%"TAP"
"1","(-525,3550)","0","standard","I95";
;
CDS_LIB"standard"
BODY_TYPE"PLUMBING"
HDL_TAP"TRUE";
"B \NAC \NWC"10;
"S \NAC"
BN"15"127;
%"TAP"
"1","(-525,3600)","0","standard","I96";
;
CDS_LIB"standard"
BODY_TYPE"PLUMBING"
HDL_TAP"TRUE";
"B \NAC \NWC"10;
"S \NAC"
BN"16"128;
%"TAP"
"1","(-525,3650)","0","standard","I97";
;
CDS_LIB"standard"
BODY_TYPE"PLUMBING"
HDL_TAP"TRUE";
"B \NAC \NWC"10;
"S \NAC"
BN"17"129;
%"TAP"
"1","(-525,3750)","0","standard","I98";
;
CDS_LIB"standard"
BODY_TYPE"PLUMBING"
HDL_TAP"TRUE";
"B \NAC \NWC"10;
"S \NAC"
BN"19"131;
%"TAP"
"1","(-525,3700)","0","standard","I99";
;
CDS_LIB"standard"
BODY_TYPE"PLUMBING"
HDL_TAP"TRUE";
"B \NAC \NWC"10;
"S \NAC"
BN"18"130;
END.
